(kicad_pcb
	(version 20260206)
	(generator "pcbnew")
	(generator_version "10.0")
	(general
		(thickness 1.6)
		(legacy_teardrops no)
	)
	(paper "A4")
	(title_block
		(title "Bryce Canyon_IOM_IOC_16318-2_OCP.brd")
		(comment 1 "Bryce Canyon / footprint 592 of 1605 (U1), pads 348-467 of 896")
	)
	(layers
		(0 "F.Cu" signal "TOP")
		(4 "In1.Cu" signal "L2GND")
		(6 "In2.Cu" signal "L3")
		(8 "In3.Cu" signal "L4VCC")
		(10 "In4.Cu" signal "L5VCC")
		(12 "In5.Cu" signal "L6")
		(14 "In6.Cu" signal "L7GND")
		(2 "B.Cu" signal "BOTTOM")
		(9 "F.Adhes" user "F.Adhesive")
		(11 "B.Adhes" user "B.Adhesive")
		(13 "F.Paste" user "Package Geometry/Pastemask Top")
		(15 "B.Paste" user "Package Geometry/Pastemask Bottom")
		(5 "F.SilkS" user "Ref Des/Silkscreen Top")
		(7 "B.SilkS" user "Ref Des/Silkscreen Bottom")
		(1 "F.Mask" user "Board Geometry/Soldermask Top")
		(3 "B.Mask" user "Board Geometry/Soldermask Bottom")
		(17 "Dwgs.User" user "User.Drawings")
		(19 "Cmts.User" user "User.Comments")
		(21 "Eco1.User" user "User.Eco1")
		(23 "Eco2.User" user "User.Eco2")
		(25 "Edge.Cuts" user "Board Geometry/Outline")
		(27 "Margin" user)
		(31 "F.CrtYd" user "Package Geometry/Place Bound Top")
		(29 "B.CrtYd" user "Package Geometry/Place Bound Bottom")
		(35 "F.Fab" user "Ref Des/Assembly Top")
		(33 "B.Fab" user "Ref Des/Assembly Bottom")
	)
	(footprint ""
		(layer "F.Cu")
		(at 192.79997 -65.099946 180)
		(property "Reference" "U1"
			(at 0 0 180)
			(layer "F.SilkS")
			(hide yes)
			(effects
				(font
					(size 1.27 1.27)
				)
			)
		)
		(property "Value" "SAS3008C0-1-DB-500020657-1-GP"
			(at -20.374102 -5.0292 180)
			(unlocked yes)
			(layer "F.Fab")
			(hide yes)
			(effects
				(font
					(size 1.016 1.016)
					(thickness 0.1524)
				)
			)
		)
		(property "Device Type" "BGA896D25H78"
			(at -20.374102 -6.5532 180)
			(unlocked yes)
			(layer "F.Fab")
			(hide yes)
			(effects
				(font
					(size 1.016 1.016)
					(thickness 0.1524)
				)
			)
		)
		(duplicate_pad_numbers_are_jumpers no)
		(pad "B22" smd circle
			(at 5.199888 -10.80008 180)
			(size 0.3556 0.3556)
			(layers "F.Cu" "F.Mask" "F.Paste")
			(net "XM_OE_N")
		)
		(pad "B23" smd circle
			(at 5.999988 -10.80008 180)
			(size 0.3556 0.3556)
			(layers "F.Cu" "F.Mask" "F.Paste")
			(net "Net_1202")
		)
		(pad "B24" smd circle
			(at 6.800088 -10.80008 180)
			(size 0.3556 0.3556)
			(layers "F.Cu" "F.Mask" "F.Paste")
			(net "Net_1203")
		)
		(pad "B25" smd circle
			(at 7.599934 -10.80008 180)
			(size 0.3556 0.3556)
			(layers "F.Cu" "F.Mask" "F.Paste")
			(net "XM_ADDR_0")
		)
		(pad "B26" smd circle
			(at 8.400034 -10.80008 180)
			(size 0.3556 0.3556)
			(layers "F.Cu" "F.Mask" "F.Paste")
			(net "XM_ALE")
		)
		(pad "B27" smd circle
			(at 9.19988 -10.80008 180)
			(size 0.3556 0.3556)
			(layers "F.Cu" "F.Mask" "F.Paste")
			(net "XM_ADDR_1")
		)
		(pad "B28" smd circle
			(at 9.99998 -10.80008 180)
			(size 0.4064 0.4064)
			(layers "F.Cu" "F.Mask" "F.Paste")
			(net "XM_ADDR_6")
		)
		(pad "B29" smd circle
			(at 10.80008 -10.80008 180)
			(size 0.4064 0.4064)
			(layers "F.Cu" "F.Mask" "F.Paste")
			(net "XM_ADDR_8")
		)
		(pad "B30" smd circle
			(at 11.599926 -10.80008 180)
			(size 0.4064 0.4064)
			(layers "F.Cu" "F.Mask" "F.Paste")
			(net "XM_ADDR_7")
		)
		(pad "C1" smd circle
			(at -11.599926 -9.99998 180)
			(size 0.4064 0.4064)
			(layers "F.Cu" "F.Mask" "F.Paste")
			(net "GND")
		)
		(pad "C2" smd circle
			(at -10.80008 -9.99998 180)
			(size 0.4064 0.4064)
			(layers "F.Cu" "F.Mask" "F.Paste")
			(net "Net_1219")
		)
		(pad "C3" smd circle
			(at -9.99998 -9.99998 180)
			(size 0.4064 0.4064)
			(layers "F.Cu" "F.Mask" "F.Paste")
			(net "Net_1220")
		)
		(pad "C4" smd circle
			(at -9.19988 -9.99998 180)
			(size 0.3556 0.3556)
			(layers "F.Cu" "F.Mask" "F.Paste")
			(net "Net_1221")
		)
		(pad "C5" smd circle
			(at -8.400034 -9.99998 180)
			(size 0.3556 0.3556)
			(layers "F.Cu" "F.Mask" "F.Paste")
			(net "GND")
		)
		(pad "C6" smd circle
			(at -7.599934 -9.99998 180)
			(size 0.3556 0.3556)
			(layers "F.Cu" "F.Mask" "F.Paste")
			(net "ICE1_TRST#")
		)
		(pad "C7" smd circle
			(at -6.800088 -9.99998 180)
			(size 0.3556 0.3556)
			(layers "F.Cu" "F.Mask" "F.Paste")
			(net "ICE0_TMS")
		)
		(pad "C8" smd circle
			(at -5.999988 -9.99998 180)
			(size 0.3556 0.3556)
			(layers "F.Cu" "F.Mask" "F.Paste")
			(net "ICE0_TDO")
		)
		(pad "C9" smd circle
			(at -5.199888 -9.99998 180)
			(size 0.3556 0.3556)
			(layers "F.Cu" "F.Mask" "F.Paste")
			(net "Net_1222")
		)
		(pad "C10" smd circle
			(at -4.400042 -9.99998 180)
			(size 0.3556 0.3556)
			(layers "F.Cu" "F.Mask" "F.Paste")
			(net "Net_1223")
		)
		(pad "C11" smd circle
			(at -3.599942 -9.99998 180)
			(size 0.3556 0.3556)
			(layers "F.Cu" "F.Mask" "F.Paste")
			(net "GND")
		)
		(pad "C12" smd circle
			(at -2.800096 -9.99998 180)
			(size 0.3556 0.3556)
			(layers "F.Cu" "F.Mask" "F.Paste")
			(net "PWRGD_P1V8")
		)
		(pad "C13" smd circle
			(at -1.999996 -9.99998 180)
			(size 0.3556 0.3556)
			(layers "F.Cu" "F.Mask" "F.Paste")
			(net "Net_1207")
		)
		(pad "C14" smd circle
			(at -1.199896 -9.99998 180)
			(size 0.3556 0.3556)
			(layers "F.Cu" "F.Mask" "F.Paste")
			(net "GND")
		)
		(pad "C15" smd circle
			(at -0.40005 -9.99998 180)
			(size 0.3556 0.3556)
			(layers "F.Cu" "F.Mask" "F.Paste")
			(net "GND")
		)
		(pad "C16" smd circle
			(at 0.40005 -9.99998 180)
			(size 0.3556 0.3556)
			(layers "F.Cu" "F.Mask" "F.Paste")
			(net "LSI_TN")
		)
		(pad "C17" smd circle
			(at 1.199896 -9.99998 180)
			(size 0.3556 0.3556)
			(layers "F.Cu" "F.Mask" "F.Paste")
			(net "JTAG_IOC_TCK")
		)
		(pad "C18" smd circle
			(at 1.999996 -9.99998 180)
			(size 0.3556 0.3556)
			(layers "F.Cu" "F.Mask" "F.Paste")
			(net "IOC_TDO")
		)
		(pad "C19" smd circle
			(at 2.800096 -9.99998 180)
			(size 0.3556 0.3556)
			(layers "F.Cu" "F.Mask" "F.Paste")
			(net "XM_DATA_15")
		)
		(pad "C20" smd circle
			(at 3.599942 -9.99998 180)
			(size 0.3556 0.3556)
			(layers "F.Cu" "F.Mask" "F.Paste")
			(net "XM_DATA_6")
		)
		(pad "C21" smd circle
			(at 4.400042 -9.99998 180)
			(size 0.3556 0.3556)
			(layers "F.Cu" "F.Mask" "F.Paste")
			(net "XM_DATA_8")
		)
		(pad "C22" smd circle
			(at 5.199888 -9.99998 180)
			(size 0.3556 0.3556)
			(layers "F.Cu" "F.Mask" "F.Paste")
			(net "XM_DATA_5")
		)
		(pad "C23" smd circle
			(at 5.999988 -9.99998 180)
			(size 0.3556 0.3556)
			(layers "F.Cu" "F.Mask" "F.Paste")
			(net "XM_CLE")
		)
		(pad "C24" smd circle
			(at 6.800088 -9.99998 180)
			(size 0.3556 0.3556)
			(layers "F.Cu" "F.Mask" "F.Paste")
			(net "XM_DATA_7")
		)
		(pad "C25" smd circle
			(at 7.599934 -9.99998 180)
			(size 0.3556 0.3556)
			(layers "F.Cu" "F.Mask" "F.Paste")
			(net "XM_DATA_10")
		)
		(pad "C26" smd circle
			(at 8.400034 -9.99998 180)
			(size 0.3556 0.3556)
			(layers "F.Cu" "F.Mask" "F.Paste")
			(net "XM_DATA_9")
		)
		(pad "C27" smd circle
			(at 9.19988 -9.99998 180)
			(size 0.3556 0.3556)
			(layers "F.Cu" "F.Mask" "F.Paste")
			(net "XM_ADDR_2")
		)
		(pad "C28" smd circle
			(at 9.99998 -9.99998 180)
			(size 0.4064 0.4064)
			(layers "F.Cu" "F.Mask" "F.Paste")
			(net "XM_ADDR_5")
		)
		(pad "C29" smd circle
			(at 10.80008 -9.99998 180)
			(size 0.4064 0.4064)
			(layers "F.Cu" "F.Mask" "F.Paste")
			(net "XM_ADDR_11")
		)
		(pad "C30" smd circle
			(at 11.599926 -9.99998 180)
			(size 0.4064 0.4064)
			(layers "F.Cu" "F.Mask" "F.Paste")
			(net "XM_ADDR_13")
		)
		(pad "D1" smd circle
			(at -11.599926 -9.19988 180)
			(size 0.3556 0.3556)
			(layers "F.Cu" "F.Mask" "F.Paste")
			(net "Net_1250")
		)
		(pad "D2" smd circle
			(at -10.80008 -9.19988 180)
			(size 0.3556 0.3556)
			(layers "F.Cu" "F.Mask" "F.Paste")
			(net "Net_1224")
		)
		(pad "D3" smd circle
			(at -9.99998 -9.19988 180)
			(size 0.3556 0.3556)
			(layers "F.Cu" "F.Mask" "F.Paste")
			(net "Net_1225")
		)
		(pad "D4" smd circle
			(at -9.19988 -9.19988 180)
			(size 0.3556 0.3556)
			(layers "F.Cu" "F.Mask" "F.Paste")
			(net "P1V8")
		)
		(pad "D5" smd circle
			(at -8.400034 -9.19988 180)
			(size 0.3556 0.3556)
			(layers "F.Cu" "F.Mask" "F.Paste")
			(net "GND")
		)
		(pad "D6" smd circle
			(at -7.599934 -9.19988 180)
			(size 0.3556 0.3556)
			(layers "F.Cu" "F.Mask" "F.Paste")
			(net "P1V8")
		)
		(pad "D7" smd circle
			(at -6.800088 -9.19988 180)
			(size 0.3556 0.3556)
			(layers "F.Cu" "F.Mask" "F.Paste")
			(net "GND")
		)
		(pad "D8" smd circle
			(at -5.999988 -9.19988 180)
			(size 0.3556 0.3556)
			(layers "F.Cu" "F.Mask" "F.Paste")
			(net "P1V8")
		)
		(pad "D9" smd circle
			(at -5.199888 -9.19988 180)
			(size 0.3556 0.3556)
			(layers "F.Cu" "F.Mask" "F.Paste")
			(net "GND")
		)
		(pad "D10" smd circle
			(at -4.400042 -9.19988 180)
			(size 0.3556 0.3556)
			(layers "F.Cu" "F.Mask" "F.Paste")
			(net "P1V8")
		)
		(pad "D11" smd circle
			(at -3.599942 -9.19988 180)
			(size 0.3556 0.3556)
			(layers "F.Cu" "F.Mask" "F.Paste")
			(net "GND")
		)
		(pad "D12" smd circle
			(at -2.800096 -9.19988 180)
			(size 0.3556 0.3556)
			(layers "F.Cu" "F.Mask" "F.Paste")
			(net "GND")
		)
		(pad "D13" smd circle
			(at -1.999996 -9.19988 180)
			(size 0.3556 0.3556)
			(layers "F.Cu" "F.Mask" "F.Paste")
			(net "GND")
		)
		(pad "D14" smd circle
			(at -1.199896 -9.19988 180)
			(size 0.3556 0.3556)
			(layers "F.Cu" "F.Mask" "F.Paste")
			(net "GND")
		)
		(pad "D15" smd circle
			(at -0.40005 -9.19988 180)
			(size 0.3556 0.3556)
			(layers "F.Cu" "F.Mask" "F.Paste")
			(net "GND")
		)
		(pad "D16" smd circle
			(at 0.40005 -9.19988 180)
			(size 0.3556 0.3556)
			(layers "F.Cu" "F.Mask" "F.Paste")
			(net "P1V8")
		)
		(pad "D17" smd circle
			(at 1.199896 -9.19988 180)
			(size 0.3556 0.3556)
			(layers "F.Cu" "F.Mask" "F.Paste")
			(net "GND")
		)
		(pad "D18" smd circle
			(at 1.999996 -9.19988 180)
			(size 0.3556 0.3556)
			(layers "F.Cu" "F.Mask" "F.Paste")
			(net "P1V8")
		)
		(pad "D19" smd circle
			(at 2.800096 -9.19988 180)
			(size 0.3556 0.3556)
			(layers "F.Cu" "F.Mask" "F.Paste")
			(net "GND")
		)
		(pad "D20" smd circle
			(at 3.599942 -9.19988 180)
			(size 0.3556 0.3556)
			(layers "F.Cu" "F.Mask" "F.Paste")
			(net "P1V8")
		)
		(pad "D21" smd circle
			(at 4.400042 -9.19988 180)
			(size 0.3556 0.3556)
			(layers "F.Cu" "F.Mask" "F.Paste")
			(net "GND")
		)
		(pad "D22" smd circle
			(at 5.199888 -9.19988 180)
			(size 0.3556 0.3556)
			(layers "F.Cu" "F.Mask" "F.Paste")
			(net "P1V8")
		)
		(pad "D23" smd circle
			(at 5.999988 -9.19988 180)
			(size 0.3556 0.3556)
			(layers "F.Cu" "F.Mask" "F.Paste")
			(net "GND")
		)
		(pad "D24" smd circle
			(at 6.800088 -9.19988 180)
			(size 0.3556 0.3556)
			(layers "F.Cu" "F.Mask" "F.Paste")
			(net "P1V8")
		)
		(pad "D25" smd circle
			(at 7.599934 -9.19988 180)
			(size 0.3556 0.3556)
			(layers "F.Cu" "F.Mask" "F.Paste")
			(net "GND")
		)
		(pad "D26" smd circle
			(at 8.400034 -9.19988 180)
			(size 0.3556 0.3556)
			(layers "F.Cu" "F.Mask" "F.Paste")
			(net "P1V8")
		)
		(pad "D27" smd circle
			(at 9.19988 -9.19988 180)
			(size 0.3556 0.3556)
			(layers "F.Cu" "F.Mask" "F.Paste")
			(net "GND")
		)
		(pad "D28" smd circle
			(at 9.99998 -9.19988 180)
			(size 0.3556 0.3556)
			(layers "F.Cu" "F.Mask" "F.Paste")
			(net "XM_ADDR_9")
		)
		(pad "D29" smd circle
			(at 10.80008 -9.19988 180)
			(size 0.3556 0.3556)
			(layers "F.Cu" "F.Mask" "F.Paste")
			(net "XM_ADDR_10")
		)
		(pad "D30" smd circle
			(at 11.599926 -9.19988 180)
			(size 0.3556 0.3556)
			(layers "F.Cu" "F.Mask" "F.Paste")
			(net "XM_ADDR_17")
		)
		(pad "E1" smd circle
			(at -11.599926 -8.400034 180)
			(size 0.3556 0.3556)
			(layers "F.Cu" "F.Mask" "F.Paste")
			(net "Net_1251")
		)
		(pad "E2" smd circle
			(at -10.80008 -8.400034 180)
			(size 0.3556 0.3556)
			(layers "F.Cu" "F.Mask" "F.Paste")
			(net "Net_1226")
		)
		(pad "E3" smd circle
			(at -9.99998 -8.400034 180)
			(size 0.3556 0.3556)
			(layers "F.Cu" "F.Mask" "F.Paste")
			(net "GND")
		)
		(pad "E4" smd circle
			(at -9.19988 -8.400034 180)
			(size 0.3556 0.3556)
			(layers "F.Cu" "F.Mask" "F.Paste")
			(net "GND")
		)
		(pad "E5" smd circle
			(at -8.400034 -8.400034 180)
			(size 0.3556 0.3556)
			(layers "F.Cu" "F.Mask" "F.Paste")
			(net "P1V8")
		)
		(pad "E6" smd circle
			(at -7.599934 -8.400034 180)
			(size 0.3556 0.3556)
			(layers "F.Cu" "F.Mask" "F.Paste")
			(net "GND")
		)
		(pad "E7" smd circle
			(at -6.800088 -8.400034 180)
			(size 0.3556 0.3556)
			(layers "F.Cu" "F.Mask" "F.Paste")
			(net "P1V8")
		)
		(pad "E8" smd circle
			(at -5.999988 -8.400034 180)
			(size 0.3556 0.3556)
			(layers "F.Cu" "F.Mask" "F.Paste")
			(net "GND")
		)
		(pad "E9" smd circle
			(at -5.199888 -8.400034 180)
			(size 0.3556 0.3556)
			(layers "F.Cu" "F.Mask" "F.Paste")
			(net "P1V8")
		)
		(pad "E10" smd circle
			(at -4.400042 -8.400034 180)
			(size 0.3556 0.3556)
			(layers "F.Cu" "F.Mask" "F.Paste")
			(net "GND")
		)
		(pad "E11" smd circle
			(at -3.599942 -8.400034 180)
			(size 0.3556 0.3556)
			(layers "F.Cu" "F.Mask" "F.Paste")
			(net "GND")
		)
		(pad "E12" smd circle
			(at -2.800096 -8.400034 180)
			(size 0.3556 0.3556)
			(layers "F.Cu" "F.Mask" "F.Paste")
			(net "GND")
		)
		(pad "E13" smd circle
			(at -1.999996 -8.400034 180)
			(size 0.3556 0.3556)
			(layers "F.Cu" "F.Mask" "F.Paste")
			(net "GND")
		)
		(pad "E14" smd circle
			(at -1.199896 -8.400034 180)
			(size 0.3556 0.3556)
			(layers "F.Cu" "F.Mask" "F.Paste")
			(net "GND")
		)
		(pad "E15" smd circle
			(at -0.40005 -8.400034 180)
			(size 0.3556 0.3556)
			(layers "F.Cu" "F.Mask" "F.Paste")
			(net "P1V8")
		)
		(pad "E16" smd circle
			(at 0.40005 -8.400034 180)
			(size 0.3556 0.3556)
			(layers "F.Cu" "F.Mask" "F.Paste")
			(net "GND")
		)
		(pad "E17" smd circle
			(at 1.199896 -8.400034 180)
			(size 0.3556 0.3556)
			(layers "F.Cu" "F.Mask" "F.Paste")
			(net "P1V8")
		)
		(pad "E18" smd circle
			(at 1.999996 -8.400034 180)
			(size 0.3556 0.3556)
			(layers "F.Cu" "F.Mask" "F.Paste")
			(net "GND")
		)
		(pad "E19" smd circle
			(at 2.800096 -8.400034 180)
			(size 0.3556 0.3556)
			(layers "F.Cu" "F.Mask" "F.Paste")
			(net "P1V8")
		)
		(pad "E20" smd circle
			(at 3.599942 -8.400034 180)
			(size 0.3556 0.3556)
			(layers "F.Cu" "F.Mask" "F.Paste")
			(net "GND")
		)
		(pad "E21" smd circle
			(at 4.400042 -8.400034 180)
			(size 0.3556 0.3556)
			(layers "F.Cu" "F.Mask" "F.Paste")
			(net "P1V8")
		)
		(pad "E22" smd circle
			(at 5.199888 -8.400034 180)
			(size 0.3556 0.3556)
			(layers "F.Cu" "F.Mask" "F.Paste")
			(net "GND")
		)
		(pad "E23" smd circle
			(at 5.999988 -8.400034 180)
			(size 0.3556 0.3556)
			(layers "F.Cu" "F.Mask" "F.Paste")
			(net "P1V8")
		)
		(pad "E24" smd circle
			(at 6.800088 -8.400034 180)
			(size 0.3556 0.3556)
			(layers "F.Cu" "F.Mask" "F.Paste")
			(net "GND")
		)
		(pad "E25" smd circle
			(at 7.599934 -8.400034 180)
			(size 0.3556 0.3556)
			(layers "F.Cu" "F.Mask" "F.Paste")
			(net "P1V8")
		)
		(pad "E26" smd circle
			(at 8.400034 -8.400034 180)
			(size 0.3556 0.3556)
			(layers "F.Cu" "F.Mask" "F.Paste")
			(net "GND")
		)
		(pad "E27" smd circle
			(at 9.19988 -8.400034 180)
			(size 0.3556 0.3556)
			(layers "F.Cu" "F.Mask" "F.Paste")
			(net "P1V8")
		)
		(pad "E28" smd circle
			(at 9.99998 -8.400034 180)
			(size 0.3556 0.3556)
			(layers "F.Cu" "F.Mask" "F.Paste")
			(net "XM_ADDR_12")
		)
		(pad "E29" smd circle
			(at 10.80008 -8.400034 180)
			(size 0.3556 0.3556)
			(layers "F.Cu" "F.Mask" "F.Paste")
			(net "XM_DATA_14")
		)
		(pad "E30" smd circle
			(at 11.599926 -8.400034 180)
			(size 0.3556 0.3556)
			(layers "F.Cu" "F.Mask" "F.Paste")
			(net "XM_ADDR_14")
		)
		(pad "F1" smd circle
			(at -11.599926 -7.599934 180)
			(size 0.3556 0.3556)
			(layers "F.Cu" "F.Mask" "F.Paste")
			(net "Net_1252")
		)
		(pad "F2" smd circle
			(at -10.80008 -7.599934 180)
			(size 0.3556 0.3556)
			(layers "F.Cu" "F.Mask" "F.Paste")
			(net "Net_1227")
		)
		(pad "F3" smd circle
			(at -9.99998 -7.599934 180)
			(size 0.3556 0.3556)
			(layers "F.Cu" "F.Mask" "F.Paste")
			(net "Net_1228")
		)
		(pad "F4" smd circle
			(at -9.19988 -7.599934 180)
			(size 0.3556 0.3556)
			(layers "F.Cu" "F.Mask" "F.Paste")
			(net "P1V8")
		)
		(pad "F5" smd circle
			(at -8.400034 -7.599934 180)
			(size 0.3556 0.3556)
			(layers "F.Cu" "F.Mask" "F.Paste")
			(net "GND")
		)
		(pad "F6" smd circle
			(at -7.599934 -7.599934 180)
			(size 0.3556 0.3556)
			(layers "F.Cu" "F.Mask" "F.Paste")
			(net "Net_1229")
		)
		(pad "F7" smd circle
			(at -6.800088 -7.599934 180)
			(size 0.3556 0.3556)
			(layers "F.Cu" "F.Mask" "F.Paste")
			(net "Net_1230")
		)
		(pad "F8" smd circle
			(at -5.999988 -7.599934 180)
			(size 0.3556 0.3556)
			(layers "F.Cu" "F.Mask" "F.Paste")
			(net "Net_1231")
		)
		(pad "F9" smd circle
			(at -5.199888 -7.599934 180)
			(size 0.3556 0.3556)
			(layers "F.Cu" "F.Mask" "F.Paste")
			(net "Net_1232")
		)
		(pad "F10" smd circle
			(at -4.400042 -7.599934 180)
			(size 0.3556 0.3556)
			(layers "F.Cu" "F.Mask" "F.Paste")
			(net "Net_1233")
		)
		(pad "F11" smd circle
			(at -3.599942 -7.599934 180)
			(size 0.3556 0.3556)
			(layers "F.Cu" "F.Mask" "F.Paste")
			(net "GND")
		)
		(pad "F12" smd circle
			(at -2.800096 -7.599934 180)
			(size 0.3556 0.3556)
			(layers "F.Cu" "F.Mask" "F.Paste")
			(net "GND")
		)
		(pad "F13" smd circle
			(at -1.999996 -7.599934 180)
			(size 0.3556 0.3556)
			(layers "F.Cu" "F.Mask" "F.Paste")
			(net "GND")
		)
		(pad "F14" smd circle
			(at -1.199896 -7.599934 180)
			(size 0.3556 0.3556)
			(layers "F.Cu" "F.Mask" "F.Paste")
			(net "GND")
		)
		(pad "F15" smd circle
			(at -0.40005 -7.599934 180)
			(size 0.3556 0.3556)
			(layers "F.Cu" "F.Mask" "F.Paste")
			(net "GND")
		)
		(pad "F16" smd circle
			(at 0.40005 -7.599934 180)
			(size 0.3556 0.3556)
			(layers "F.Cu" "F.Mask" "F.Paste")
			(net "GND")
		)
		(pad "F17" smd circle
			(at 1.199896 -7.599934 180)
			(size 0.3556 0.3556)
			(layers "F.Cu" "F.Mask" "F.Paste")
			(net "GND")
		)
		(pad "F18" smd circle
			(at 1.999996 -7.599934 180)
			(size 0.3556 0.3556)
			(layers "F.Cu" "F.Mask" "F.Paste")
			(net "GND")
		)
		(pad "F19" smd circle
			(at 2.800096 -7.599934 180)
			(size 0.3556 0.3556)
			(layers "F.Cu" "F.Mask" "F.Paste")
			(net "GND")
		)
		(pad "F20" smd circle
			(at 3.599942 -7.599934 180)
			(size 0.3556 0.3556)
			(layers "F.Cu" "F.Mask" "F.Paste")
			(net "GND")
		)
		(pad "F21" smd circle
			(at 4.400042 -7.599934 180)
			(size 0.3556 0.3556)
			(layers "F.Cu" "F.Mask" "F.Paste")
			(net "GND")
		)
	)
)
